# SCM (Grand Teton) — schematic netlist excerpt (pin names and nets, part order shuffled) for the footprints in the layout excerpt that follows; sources: Cadence DE-HDL packaged netlist, KiCad conversion of 12092022_DA0F0TMDCD0_F0T_Management_Board_D_brd_V3_OCP.brd

R791  Q_RES  1.69K 1% CHIP  pkg 0402LF  page 15 : A = P2V5_AUX ; B = P2V5_SENSOR
R205  Q_RES  20K 1% CHIP  pkg 0402LF  page 29 : A = DEBUG_PORT_PRSNT_R ; B = GND

(kicad_pcb
	(version 20260206)
	(generator "pcbnew")
	(generator_version "10.0")
	(general
		(thickness 1.6)
		(legacy_teardrops no)
	)
	(paper "A4")
	(title_block
		(title "12092022_DA0F0TMDCD0_F0T_Management_Board_D_brd_V3_OCP.brd")
		(comment 1 "Grand Teton / footprints 1187-1188 of 1440")
	)
	(layers
		(0 "F.Cu" signal "TOP")
		(4 "In1.Cu" signal "GND")
		(6 "In2.Cu" signal "IN1")
		(8 "In3.Cu" signal "GND1")
		(10 "In4.Cu" signal "IN2")
		(12 "In5.Cu" signal "VCC")
		(14 "In6.Cu" signal "VCC1")
		(16 "In7.Cu" signal "IN3")
		(18 "In8.Cu" signal "GND2")
		(20 "In9.Cu" signal "IN4")
		(22 "In10.Cu" signal "GND3")
		(2 "B.Cu" signal "BOTTOM")
		(9 "F.Adhes" user "F.Adhesive")
		(11 "B.Adhes" user "B.Adhesive")
		(13 "F.Paste" user "Package Geometry/Pastemask Top")
		(15 "B.Paste" user "Package Geometry/Pastemask Bottom")
		(5 "F.SilkS" user "Ref Des/Silkscreen Top")
		(7 "B.SilkS" user "Ref Des/Silkscreen Bottom")
		(1 "F.Mask" user "Board Geometry/Soldermask Top")
		(3 "B.Mask" user "Board Geometry/Soldermask Bottom")
		(17 "Dwgs.User" user "User.Drawings")
		(19 "Cmts.User" user "User.Comments")
		(21 "Eco1.User" user "User.Eco1")
		(23 "Eco2.User" user "User.Eco2")
		(25 "Edge.Cuts" user "Board Geometry/Outline")
		(27 "Margin" user)
		(31 "F.CrtYd" user "Package Geometry/Place Bound Top")
		(29 "B.CrtYd" user "Package Geometry/Place Bound Bottom")
		(35 "F.Fab" user "Ref Des/Assembly Top")
		(33 "B.Fab" user "Ref Des/Assembly Bottom")
	)
	(footprint ""
		(layer "B.Cu")
		(at 42.926 -19.431 -90)
		(property "Reference" "R205"
			(at 0 0 90)
			(layer "B.SilkS")
			(hide yes)
			(effects
				(font
					(size 1.27 1.27)
				)
				(justify mirror)
			)
		)
		(property "Value" ""
			(at 0 0 90)
			(layer "B.Fab")
			(effects
				(font
					(size 1.27 1.27)
				)
				(justify mirror)
			)
		)
		(duplicate_pad_numbers_are_jumpers no)
		(fp_line
			(start -0.7874 0.4064)
			(end 0.7874 0.4064)
			(stroke
				(width 0.1524)
				(type default)
			)
			(layer "B.SilkS")
		)
		(fp_line
			(start 0.7874 0.4064)
			(end 0.7874 -0.4064)
			(stroke
				(width 0.1524)
				(type default)
			)
			(layer "B.SilkS")
		)
		(fp_line
			(start -0.7874 -0.4064)
			(end -0.7874 0.4064)
			(stroke
				(width 0.1524)
				(type default)
			)
			(layer "B.SilkS")
		)
		(fp_line
			(start 0.7874 -0.4064)
			(end -0.7874 -0.4064)
			(stroke
				(width 0.1524)
				(type default)
			)
			(layer "B.SilkS")
		)
		(fp_line
			(start -0.67945 0.3048)
			(end -0.120396 0.3048)
			(stroke
				(width 0.1)
				(type default)
			)
			(layer "B.Fab")
		)
		(fp_line
			(start -0.120396 0.3048)
			(end -0.120396 0.2794)
			(stroke
				(width 0.1)
				(type default)
			)
			(layer "B.Fab")
		)
		(fp_line
			(start 0.12065 0.3048)
			(end 0.67945 0.3048)
			(stroke
				(width 0.1)
				(type default)
			)
			(layer "B.Fab")
		)
		(fp_line
			(start 0.67945 0.3048)
			(end 0.67945 -0.305054)
			(stroke
				(width 0.1)
				(type default)
			)
			(layer "B.Fab")
		)
		(fp_line
			(start -0.120396 0.2794)
			(end 0.12065 0.2794)
			(stroke
				(width 0.1)
				(type default)
			)
			(layer "B.Fab")
		)
		(fp_line
			(start 0.12065 0.2794)
			(end 0.12065 0.3048)
			(stroke
				(width 0.1)
				(type default)
			)
			(layer "B.Fab")
		)
		(fp_line
			(start -0.12065 -0.2794)
			(end -0.12065 -0.3048)
			(stroke
				(width 0.1)
				(type default)
			)
			(layer "B.Fab")
		)
		(fp_line
			(start 0.12065 -0.2794)
			(end -0.12065 -0.2794)
			(stroke
				(width 0.1)
				(type default)
			)
			(layer "B.Fab")
		)
		(fp_line
			(start -0.67945 -0.3048)
			(end -0.67945 0.3048)
			(stroke
				(width 0.1)
				(type default)
			)
			(layer "B.Fab")
		)
		(fp_line
			(start -0.12065 -0.3048)
			(end -0.67945 -0.3048)
			(stroke
				(width 0.1)
				(type default)
			)
			(layer "B.Fab")
		)
		(fp_line
			(start 0.12065 -0.305054)
			(end 0.12065 -0.2794)
			(stroke
				(width 0.1)
				(type default)
			)
			(layer "B.Fab")
		)
		(fp_line
			(start 0.67945 -0.305054)
			(end 0.12065 -0.305054)
			(stroke
				(width 0.1)
				(type default)
			)
			(layer "B.Fab")
		)
		(pad "1" smd circle
			(at 0.40005 0 90)
			(size 0 0)
			(layers "B.Cu" "B.Mask" "B.Paste")
			(net "DEBUG_PORT_PRSNT_R")
		)
		(pad "2" smd circle
			(at -0.40005 0 90)
			(size 0 0)
			(layers "B.Cu" "B.Mask" "B.Paste")
			(net "GND")
		)
	)
	(footprint ""
		(layer "B.Cu")
		(at 54.308502 -70.420484 90)
		(property "Reference" "R791"
			(at 0 0 90)
			(layer "B.SilkS")
			(hide yes)
			(effects
				(font
					(size 1.27 1.27)
				)
				(justify mirror)
			)
		)
		(property "Value" ""
			(at 0 0 90)
			(layer "B.Fab")
			(effects
				(font
					(size 1.27 1.27)
				)
				(justify mirror)
			)
		)
		(duplicate_pad_numbers_are_jumpers no)
		(fp_line
			(start 0.7874 -0.4064)
			(end -0.7874 -0.4064)
			(stroke
				(width 0.1524)
				(type default)
			)
			(layer "B.SilkS")
		)
		(fp_line
			(start -0.7874 -0.4064)
			(end -0.7874 0.4064)
			(stroke
				(width 0.1524)
				(type default)
			)
			(layer "B.SilkS")
		)
		(fp_line
			(start 0.7874 0.4064)
			(end 0.7874 -0.4064)
			(stroke
				(width 0.1524)
				(type default)
			)
			(layer "B.SilkS")
		)
		(fp_line
			(start -0.7874 0.4064)
			(end 0.7874 0.4064)
			(stroke
				(width 0.1524)
				(type default)
			)
			(layer "B.SilkS")
		)
		(fp_line
			(start 0.67945 -0.305054)
			(end 0.12065 -0.305054)
			(stroke
				(width 0.1)
				(type default)
			)
			(layer "B.Fab")
		)
		(fp_line
			(start 0.12065 -0.305054)
			(end 0.12065 -0.2794)
			(stroke
				(width 0.1)
				(type default)
			)
			(layer "B.Fab")
		)
		(fp_line
			(start -0.12065 -0.3048)
			(end -0.67945 -0.3048)
			(stroke
				(width 0.1)
				(type default)
			)
			(layer "B.Fab")
		)
		(fp_line
			(start -0.67945 -0.3048)
			(end -0.67945 0.3048)
			(stroke
				(width 0.1)
				(type default)
			)
			(layer "B.Fab")
		)
		(fp_line
			(start 0.12065 -0.2794)
			(end -0.12065 -0.2794)
			(stroke
				(width 0.1)
				(type default)
			)
			(layer "B.Fab")
		)
		(fp_line
			(start -0.12065 -0.2794)
			(end -0.12065 -0.3048)
			(stroke
				(width 0.1)
				(type default)
			)
			(layer "B.Fab")
		)
		(fp_line
			(start 0.12065 0.2794)
			(end 0.12065 0.3048)
			(stroke
				(width 0.1)
				(type default)
			)
			(layer "B.Fab")
		)
		(fp_line
			(start -0.120396 0.2794)
			(end 0.12065 0.2794)
			(stroke
				(width 0.1)
				(type default)
			)
			(layer "B.Fab")
		)
		(fp_line
			(start 0.67945 0.3048)
			(end 0.67945 -0.305054)
			(stroke
				(width 0.1)
				(type default)
			)
			(layer "B.Fab")
		)
		(fp_line
			(start 0.12065 0.3048)
			(end 0.67945 0.3048)
			(stroke
				(width 0.1)
				(type default)
			)
			(layer "B.Fab")
		)
		(fp_line
			(start -0.120396 0.3048)
			(end -0.120396 0.2794)
			(stroke
				(width 0.1)
				(type default)
			)
			(layer "B.Fab")
		)
		(fp_line
			(start -0.67945 0.3048)
			(end -0.120396 0.3048)
			(stroke
				(width 0.1)
				(type default)
			)
			(layer "B.Fab")
		)
		(pad "1" smd circle
			(at 0.40005 0 270)
			(size 0 0)
			(layers "B.Cu" "B.Mask" "B.Paste")
			(net "P2V5_AUX")
		)
		(pad "2" smd circle
			(at -0.40005 0 270)
			(size 0 0)
			(layers "B.Cu" "B.Mask" "B.Paste")
			(net "P2V5_SENSOR")
		)
	)
)
